(kicad_pcb
	(version 20260206)
	(generator "pcbnew")
	(generator_version "10.0")
	(general
		(thickness 1.6)
		(legacy_teardrops no)
	)
	(paper "A4")
	(title_block
		(title "01162023_DA0F0TEBIF0_F0T_Expander_BD_F_brd_V02_OCP.brd")
		(comment 1 "Grand Teton / footprints 7483-7490 of 9728")
	)
	(layers
		(0 "F.Cu" signal "TOP")
		(4 "In1.Cu" signal "GND")
		(6 "In2.Cu" signal "VCC")
		(8 "In3.Cu" signal "VCC1")
		(10 "In4.Cu" signal "GND1")
		(12 "In5.Cu" signal "IN1")
		(14 "In6.Cu" signal "GND2")
		(16 "In7.Cu" signal "IN2")
		(18 "In8.Cu" signal "GND3")
		(20 "In9.Cu" signal "IN3")
		(22 "In10.Cu" signal "GND4")
		(24 "In11.Cu" signal "IN4")
		(26 "In12.Cu" signal "GND5")
		(28 "In13.Cu" signal "IN5")
		(30 "In14.Cu" signal "GND6")
		(32 "In15.Cu" signal "IN6")
		(34 "In16.Cu" signal "GND7")
		(2 "B.Cu" signal "BOTTOM")
		(9 "F.Adhes" user "F.Adhesive")
		(11 "B.Adhes" user "B.Adhesive")
		(13 "F.Paste" user "Package Geometry/Pastemask Top")
		(15 "B.Paste" user "Package Geometry/Pastemask Bottom")
		(5 "F.SilkS" user "Ref Des/Silkscreen Top")
		(7 "B.SilkS" user "Ref Des/Silkscreen Bottom")
		(1 "F.Mask" user "Board Geometry/Soldermask Top")
		(3 "B.Mask" user "Board Geometry/Soldermask Bottom")
		(17 "Dwgs.User" user "User.Drawings")
		(19 "Cmts.User" user "User.Comments")
		(21 "Eco1.User" user "User.Eco1")
		(23 "Eco2.User" user "User.Eco2")
		(25 "Edge.Cuts" user "Board Geometry/Outline")
		(27 "Margin" user)
		(31 "F.CrtYd" user "Package Geometry/Place Bound Top")
		(29 "B.CrtYd" user "Package Geometry/Place Bound Bottom")
		(35 "F.Fab" user "Ref Des/Assembly Top")
		(33 "B.Fab" user "Ref Des/Assembly Bottom")
	)
	(footprint ""
		(layer "B.Cu")
		(at 166.725092 -293.99992 90)
		(property "Reference" "C1382"
			(at 0 0 90)
			(layer "B.SilkS")
			(hide yes)
			(effects
				(font
					(size 1.27 1.27)
				)
				(justify mirror)
			)
		)
		(property "Value" ""
			(at 0 0 90)
			(layer "B.Fab")
			(effects
				(font
					(size 1.27 1.27)
				)
				(justify mirror)
			)
		)
		(duplicate_pad_numbers_are_jumpers no)
		(fp_line
			(start 0.299974 -0.150114)
			(end -0.299974 -0.150114)
			(stroke
				(width 0.1)
				(type default)
			)
			(layer "B.Fab")
		)
		(fp_line
			(start -0.299974 -0.150114)
			(end -0.299974 0.150114)
			(stroke
				(width 0.1)
				(type default)
			)
			(layer "B.Fab")
		)
		(fp_line
			(start 0.299974 0.150114)
			(end 0.299974 -0.150114)
			(stroke
				(width 0.1)
				(type default)
			)
			(layer "B.Fab")
		)
		(fp_line
			(start -0.299974 0.150114)
			(end 0.299974 0.150114)
			(stroke
				(width 0.1)
				(type default)
			)
			(layer "B.Fab")
		)
		(pad "1" smd rect
			(at 0.2667 0 270)
			(size 0.3048 0.381)
			(layers "B.Cu" "B.Mask" "B.Paste")
			(net "P0V8_PEX1")
		)
		(pad "2" smd rect
			(at -0.2667 0 270)
			(size 0.3048 0.381)
			(layers "B.Cu" "B.Mask" "B.Paste")
			(net "GND")
		)
	)
	(footprint ""
		(layer "B.Cu")
		(at 301.349918 -302.074834)
		(property "Reference" "C3340"
			(at 0 0 0)
			(layer "B.SilkS")
			(hide yes)
			(effects
				(font
					(size 1.27 1.27)
				)
				(justify mirror)
			)
		)
		(property "Value" ""
			(at 0 0 0)
			(layer "B.Fab")
			(effects
				(font
					(size 1.27 1.27)
				)
				(justify mirror)
			)
		)
		(duplicate_pad_numbers_are_jumpers no)
		(fp_line
			(start -0.299974 -0.150114)
			(end -0.299974 0.150114)
			(stroke
				(width 0.1)
				(type default)
			)
			(layer "B.Fab")
		)
		(fp_line
			(start -0.299974 0.150114)
			(end 0.299974 0.150114)
			(stroke
				(width 0.1)
				(type default)
			)
			(layer "B.Fab")
		)
		(fp_line
			(start 0.299974 -0.150114)
			(end -0.299974 -0.150114)
			(stroke
				(width 0.1)
				(type default)
			)
			(layer "B.Fab")
		)
		(fp_line
			(start 0.299974 0.150114)
			(end 0.299974 -0.150114)
			(stroke
				(width 0.1)
				(type default)
			)
			(layer "B.Fab")
		)
		(pad "1" smd rect
			(at 0.2667 0 180)
			(size 0.3048 0.381)
			(layers "B.Cu" "B.Mask" "B.Paste")
			(net "P1V8_PEX")
		)
		(pad "2" smd rect
			(at -0.2667 0 180)
			(size 0.3048 0.381)
			(layers "B.Cu" "B.Mask" "B.Paste")
			(net "GND")
		)
	)
	(footprint ""
		(layer "B.Cu")
		(at 44.449746 -300.174914)
		(property "Reference" "C3008"
			(at 0 0 0)
			(layer "B.SilkS")
			(hide yes)
			(effects
				(font
					(size 1.27 1.27)
				)
				(justify mirror)
			)
		)
		(property "Value" ""
			(at 0 0 0)
			(layer "B.Fab")
			(effects
				(font
					(size 1.27 1.27)
				)
				(justify mirror)
			)
		)
		(duplicate_pad_numbers_are_jumpers no)
		(fp_line
			(start -0.299974 -0.150114)
			(end -0.299974 0.150114)
			(stroke
				(width 0.1)
				(type default)
			)
			(layer "B.Fab")
		)
		(fp_line
			(start -0.299974 0.150114)
			(end 0.299974 0.150114)
			(stroke
				(width 0.1)
				(type default)
			)
			(layer "B.Fab")
		)
		(fp_line
			(start 0.299974 -0.150114)
			(end -0.299974 -0.150114)
			(stroke
				(width 0.1)
				(type default)
			)
			(layer "B.Fab")
		)
		(fp_line
			(start 0.299974 0.150114)
			(end 0.299974 -0.150114)
			(stroke
				(width 0.1)
				(type default)
			)
			(layer "B.Fab")
		)
		(pad "1" smd rect
			(at 0.2667 0 180)
			(size 0.3048 0.381)
			(layers "B.Cu" "B.Mask" "B.Paste")
			(net "P1V8_VDDA_PEX0")
		)
		(pad "2" smd rect
			(at -0.2667 0 180)
			(size 0.3048 0.381)
			(layers "B.Cu" "B.Mask" "B.Paste")
			(net "GND")
		)
	)
	(footprint ""
		(layer "B.Cu")
		(at 240.255806 -278.870664 -90)
		(property "Reference" "C4330"
			(at 0 0 90)
			(layer "B.SilkS")
			(hide yes)
			(effects
				(font
					(size 1.27 1.27)
				)
				(justify mirror)
			)
		)
		(property "Value" ""
			(at 0 0 90)
			(layer "B.Fab")
			(effects
				(font
					(size 1.27 1.27)
				)
				(justify mirror)
			)
		)
		(duplicate_pad_numbers_are_jumpers no)
		(fp_line
			(start -1.2954 0.5842)
			(end 1.2954 0.5842)
			(stroke
				(width 0.1524)
				(type default)
			)
			(layer "B.SilkS")
		)
		(fp_line
			(start 1.2954 0.5842)
			(end 1.2954 -0.5842)
			(stroke
				(width 0.1524)
				(type default)
			)
			(layer "B.SilkS")
		)
		(fp_line
			(start -1.2954 -0.5842)
			(end -1.2954 0.5842)
			(stroke
				(width 0.1524)
				(type default)
			)
			(layer "B.SilkS")
		)
		(fp_line
			(start 1.2954 -0.5842)
			(end -1.2954 -0.5842)
			(stroke
				(width 0.1524)
				(type default)
			)
			(layer "B.SilkS")
		)
		(fp_line
			(start -0.8636 0.4572)
			(end 0.8636 0.4572)
			(stroke
				(width 0.1)
				(type default)
			)
			(layer "B.Fab")
		)
		(fp_line
			(start 0.8636 0.4572)
			(end 0.8636 0.4064)
			(stroke
				(width 0.1)
				(type default)
			)
			(layer "B.Fab")
		)
		(fp_line
			(start -1.1938 0.4064)
			(end -0.8636 0.4064)
			(stroke
				(width 0.1)
				(type default)
			)
			(layer "B.Fab")
		)
		(fp_line
			(start -0.8636 0.4064)
			(end -0.8636 0.4572)
			(stroke
				(width 0.1)
				(type default)
			)
			(layer "B.Fab")
		)
		(fp_line
			(start 0.8636 0.4064)
			(end 1.1938 0.4064)
			(stroke
				(width 0.1)
				(type default)
			)
			(layer "B.Fab")
		)
		(fp_line
			(start 1.1938 0.4064)
			(end 1.1938 -0.4064)
			(stroke
				(width 0.1)
				(type default)
			)
			(layer "B.Fab")
		)
		(fp_line
			(start -1.1938 -0.4064)
			(end -1.1938 0.4064)
			(stroke
				(width 0.1)
				(type default)
			)
			(layer "B.Fab")
		)
		(fp_line
			(start -0.8636 -0.4064)
			(end -1.1938 -0.4064)
			(stroke
				(width 0.1)
				(type default)
			)
			(layer "B.Fab")
		)
		(fp_line
			(start 0.8636 -0.4064)
			(end 0.8636 -0.4572)
			(stroke
				(width 0.1)
				(type default)
			)
			(layer "B.Fab")
		)
		(fp_line
			(start 1.1938 -0.4064)
			(end 0.8636 -0.4064)
			(stroke
				(width 0.1)
				(type default)
			)
			(layer "B.Fab")
		)
		(fp_line
			(start -0.8636 -0.4572)
			(end -0.8636 -0.4064)
			(stroke
				(width 0.1)
				(type default)
			)
			(layer "B.Fab")
		)
		(fp_line
			(start 0.8636 -0.4572)
			(end -0.8636 -0.4572)
			(stroke
				(width 0.1)
				(type default)
			)
			(layer "B.Fab")
		)
		(pad "1" smd rect
			(at 0.7366 0 180)
			(size 0.7112 0.8128)
			(layers "B.Cu" "B.Mask" "B.Paste")
			(net "P1V25_PEX2")
		)
		(pad "2" smd rect
			(at -0.7366 0 180)
			(size 0.7112 0.8128)
			(layers "B.Cu" "B.Mask" "B.Paste")
			(net "GND")
		)
	)
	(footprint ""
		(layer "B.Cu")
		(at 246.804688 -312.434478 90)
		(property "Reference" "R4437"
			(at 0 0 90)
			(layer "B.SilkS")
			(hide yes)
			(effects
				(font
					(size 1.27 1.27)
				)
				(justify mirror)
			)
		)
		(property "Value" ""
			(at 0 0 90)
			(layer "B.Fab")
			(effects
				(font
					(size 1.27 1.27)
				)
				(justify mirror)
			)
		)
		(duplicate_pad_numbers_are_jumpers no)
		(fp_line
			(start 0.7874 -0.4064)
			(end -0.7874 -0.4064)
			(stroke
				(width 0.1524)
				(type default)
			)
			(layer "B.SilkS")
		)
		(fp_line
			(start -0.7874 -0.4064)
			(end -0.7874 0.4064)
			(stroke
				(width 0.1524)
				(type default)
			)
			(layer "B.SilkS")
		)
		(fp_line
			(start 0.7874 0.4064)
			(end 0.7874 -0.4064)
			(stroke
				(width 0.1524)
				(type default)
			)
			(layer "B.SilkS")
		)
		(fp_line
			(start -0.7874 0.4064)
			(end 0.7874 0.4064)
			(stroke
				(width 0.1524)
				(type default)
			)
			(layer "B.SilkS")
		)
		(fp_line
			(start 0.67945 -0.305054)
			(end 0.12065 -0.305054)
			(stroke
				(width 0.1)
				(type default)
			)
			(layer "B.Fab")
		)
		(fp_line
			(start 0.12065 -0.305054)
			(end 0.12065 -0.2794)
			(stroke
				(width 0.1)
				(type default)
			)
			(layer "B.Fab")
		)
		(fp_line
			(start -0.12065 -0.3048)
			(end -0.67945 -0.3048)
			(stroke
				(width 0.1)
				(type default)
			)
			(layer "B.Fab")
		)
		(fp_line
			(start -0.67945 -0.3048)
			(end -0.67945 0.3048)
			(stroke
				(width 0.1)
				(type default)
			)
			(layer "B.Fab")
		)
		(fp_line
			(start 0.12065 -0.2794)
			(end -0.12065 -0.2794)
			(stroke
				(width 0.1)
				(type default)
			)
			(layer "B.Fab")
		)
		(fp_line
			(start -0.12065 -0.2794)
			(end -0.12065 -0.3048)
			(stroke
				(width 0.1)
				(type default)
			)
			(layer "B.Fab")
		)
		(fp_line
			(start 0.12065 0.2794)
			(end 0.12065 0.3048)
			(stroke
				(width 0.1)
				(type default)
			)
			(layer "B.Fab")
		)
		(fp_line
			(start -0.120396 0.2794)
			(end 0.12065 0.2794)
			(stroke
				(width 0.1)
				(type default)
			)
			(layer "B.Fab")
		)
		(fp_line
			(start 0.67945 0.3048)
			(end 0.67945 -0.305054)
			(stroke
				(width 0.1)
				(type default)
			)
			(layer "B.Fab")
		)
		(fp_line
			(start 0.12065 0.3048)
			(end 0.67945 0.3048)
			(stroke
				(width 0.1)
				(type default)
			)
			(layer "B.Fab")
		)
		(fp_line
			(start -0.120396 0.3048)
			(end -0.120396 0.2794)
			(stroke
				(width 0.1)
				(type default)
			)
			(layer "B.Fab")
		)
		(fp_line
			(start -0.67945 0.3048)
			(end -0.120396 0.3048)
			(stroke
				(width 0.1)
				(type default)
			)
			(layer "B.Fab")
		)
		(pad "1" smd circle
			(at 0.40005 0 270)
			(size 0 0)
			(layers "B.Cu" "B.Mask" "B.Paste")
			(net "PWRGD_P1V25_PEX2_R")
		)
		(pad "2" smd circle
			(at -0.40005 0 270)
			(size 0 0)
			(layers "B.Cu" "B.Mask" "B.Paste")
			(net "PWRGD_P1V25_PEX2")
		)
	)
	(footprint ""
		(layer "B.Cu")
		(at 66.076576 -111.334042 180)
		(property "Reference" "R87"
			(at 0 0 0)
			(layer "B.SilkS")
			(hide yes)
			(effects
				(font
					(size 1.27 1.27)
				)
				(justify mirror)
			)
		)
		(property "Value" ""
			(at 0 0 0)
			(layer "B.Fab")
			(effects
				(font
					(size 1.27 1.27)
				)
				(justify mirror)
			)
		)
		(duplicate_pad_numbers_are_jumpers no)
		(fp_line
			(start 0.7874 0.4064)
			(end 0.7874 -0.4064)
			(stroke
				(width 0.1524)
				(type default)
			)
			(layer "B.SilkS")
		)
		(fp_line
			(start 0.7874 -0.4064)
			(end -0.7874 -0.4064)
			(stroke
				(width 0.1524)
				(type default)
			)
			(layer "B.SilkS")
		)
		(fp_line
			(start -0.7874 0.4064)
			(end 0.7874 0.4064)
			(stroke
				(width 0.1524)
				(type default)
			)
			(layer "B.SilkS")
		)
		(fp_line
			(start -0.7874 -0.4064)
			(end -0.7874 0.4064)
			(stroke
				(width 0.1524)
				(type default)
			)
			(layer "B.SilkS")
		)
		(fp_line
			(start 0.67945 0.3048)
			(end 0.67945 -0.305054)
			(stroke
				(width 0.1)
				(type default)
			)
			(layer "B.Fab")
		)
		(fp_line
			(start 0.67945 -0.305054)
			(end 0.12065 -0.305054)
			(stroke
				(width 0.1)
				(type default)
			)
			(layer "B.Fab")
		)
		(fp_line
			(start 0.12065 0.3048)
			(end 0.67945 0.3048)
			(stroke
				(width 0.1)
				(type default)
			)
			(layer "B.Fab")
		)
		(fp_line
			(start 0.12065 0.2794)
			(end 0.12065 0.3048)
			(stroke
				(width 0.1)
				(type default)
			)
			(layer "B.Fab")
		)
		(fp_line
			(start 0.12065 -0.2794)
			(end -0.12065 -0.2794)
			(stroke
				(width 0.1)
				(type default)
			)
			(layer "B.Fab")
		)
		(fp_line
			(start 0.12065 -0.305054)
			(end 0.12065 -0.2794)
			(stroke
				(width 0.1)
				(type default)
			)
			(layer "B.Fab")
		)
		(fp_line
			(start -0.120396 0.3048)
			(end -0.120396 0.2794)
			(stroke
				(width 0.1)
				(type default)
			)
			(layer "B.Fab")
		)
		(fp_line
			(start -0.120396 0.2794)
			(end 0.12065 0.2794)
			(stroke
				(width 0.1)
				(type default)
			)
			(layer "B.Fab")
		)
		(fp_line
			(start -0.12065 -0.2794)
			(end -0.12065 -0.3048)
			(stroke
				(width 0.1)
				(type default)
			)
			(layer "B.Fab")
		)
		(fp_line
			(start -0.12065 -0.3048)
			(end -0.67945 -0.3048)
			(stroke
				(width 0.1)
				(type default)
			)
			(layer "B.Fab")
		)
		(fp_line
			(start -0.67945 0.3048)
			(end -0.120396 0.3048)
			(stroke
				(width 0.1)
				(type default)
			)
			(layer "B.Fab")
		)
		(fp_line
			(start -0.67945 -0.3048)
			(end -0.67945 0.3048)
			(stroke
				(width 0.1)
				(type default)
			)
			(layer "B.Fab")
		)
		(pad "1" smd circle
			(at 0.40005 0)
			(size 0 0)
			(layers "B.Cu" "B.Mask" "B.Paste")
			(net "RST_SMB_NIC_MUX_R_N")
		)
		(pad "2" smd circle
			(at -0.40005 0)
			(size 0 0)
			(layers "B.Cu" "B.Mask" "B.Paste")
			(net "RST_SMB_NIC1_MUX_N")
		)
	)
	(footprint ""
		(layer "B.Cu")
		(at 183.3499 -288.299906 90)
		(property "Reference" "C3103"
			(at 0 0 90)
			(layer "B.SilkS")
			(hide yes)
			(effects
				(font
					(size 1.27 1.27)
				)
				(justify mirror)
			)
		)
		(property "Value" ""
			(at 0 0 90)
			(layer "B.Fab")
			(effects
				(font
					(size 1.27 1.27)
				)
				(justify mirror)
			)
		)
		(duplicate_pad_numbers_are_jumpers no)
		(fp_line
			(start 0.299974 -0.150114)
			(end -0.299974 -0.150114)
			(stroke
				(width 0.1)
				(type default)
			)
			(layer "B.Fab")
		)
		(fp_line
			(start -0.299974 -0.150114)
			(end -0.299974 0.150114)
			(stroke
				(width 0.1)
				(type default)
			)
			(layer "B.Fab")
		)
		(fp_line
			(start 0.299974 0.150114)
			(end 0.299974 -0.150114)
			(stroke
				(width 0.1)
				(type default)
			)
			(layer "B.Fab")
		)
		(fp_line
			(start -0.299974 0.150114)
			(end 0.299974 0.150114)
			(stroke
				(width 0.1)
				(type default)
			)
			(layer "B.Fab")
		)
		(pad "1" smd rect
			(at 0.2667 0 270)
			(size 0.3048 0.381)
			(layers "B.Cu" "B.Mask" "B.Paste")
			(net "P1V25_PEX1")
		)
		(pad "2" smd rect
			(at -0.2667 0 270)
			(size 0.3048 0.381)
			(layers "B.Cu" "B.Mask" "B.Paste")
			(net "GND")
		)
	)
	(footprint ""
		(layer "B.Cu")
		(at 375.58853 -235.540296 180)
		(property "Reference" "R912"
			(at 0 0 0)
			(layer "B.SilkS")
			(hide yes)
			(effects
				(font
					(size 1.27 1.27)
				)
				(justify mirror)
			)
		)
		(property "Value" ""
			(at 0 0 0)
			(layer "B.Fab")
			(effects
				(font
					(size 1.27 1.27)
				)
				(justify mirror)
			)
		)
		(duplicate_pad_numbers_are_jumpers no)
		(fp_line
			(start 0.7874 0.4064)
			(end 0.7874 -0.4064)
			(stroke
				(width 0.1524)
				(type default)
			)
			(layer "B.SilkS")
		)
		(fp_line
			(start 0.7874 -0.4064)
			(end -0.7874 -0.4064)
			(stroke
				(width 0.1524)
				(type default)
			)
			(layer "B.SilkS")
		)
		(fp_line
			(start -0.7874 0.4064)
			(end 0.7874 0.4064)
			(stroke
				(width 0.1524)
				(type default)
			)
			(layer "B.SilkS")
		)
		(fp_line
			(start -0.7874 -0.4064)
			(end -0.7874 0.4064)
			(stroke
				(width 0.1524)
				(type default)
			)
			(layer "B.SilkS")
		)
		(fp_line
			(start 0.67945 0.3048)
			(end 0.67945 -0.305054)
			(stroke
				(width 0.1)
				(type default)
			)
			(layer "B.Fab")
		)
		(fp_line
			(start 0.67945 -0.305054)
			(end 0.12065 -0.305054)
			(stroke
				(width 0.1)
				(type default)
			)
			(layer "B.Fab")
		)
		(fp_line
			(start 0.12065 0.3048)
			(end 0.67945 0.3048)
			(stroke
				(width 0.1)
				(type default)
			)
			(layer "B.Fab")
		)
		(fp_line
			(start 0.12065 0.2794)
			(end 0.12065 0.3048)
			(stroke
				(width 0.1)
				(type default)
			)
			(layer "B.Fab")
		)
		(fp_line
			(start 0.12065 -0.2794)
			(end -0.12065 -0.2794)
			(stroke
				(width 0.1)
				(type default)
			)
			(layer "B.Fab")
		)
		(fp_line
			(start 0.12065 -0.305054)
			(end 0.12065 -0.2794)
			(stroke
				(width 0.1)
				(type default)
			)
			(layer "B.Fab")
		)
		(fp_line
			(start -0.120396 0.3048)
			(end -0.120396 0.2794)
			(stroke
				(width 0.1)
				(type default)
			)
			(layer "B.Fab")
		)
		(fp_line
			(start -0.120396 0.2794)
			(end 0.12065 0.2794)
			(stroke
				(width 0.1)
				(type default)
			)
			(layer "B.Fab")
		)
		(fp_line
			(start -0.12065 -0.2794)
			(end -0.12065 -0.3048)
			(stroke
				(width 0.1)
				(type default)
			)
			(layer "B.Fab")
		)
		(fp_line
			(start -0.12065 -0.3048)
			(end -0.67945 -0.3048)
			(stroke
				(width 0.1)
				(type default)
			)
			(layer "B.Fab")
		)
		(fp_line
			(start -0.67945 0.3048)
			(end -0.120396 0.3048)
			(stroke
				(width 0.1)
				(type default)
			)
			(layer "B.Fab")
		)
		(fp_line
			(start -0.67945 -0.3048)
			(end -0.67945 0.3048)
			(stroke
				(width 0.1)
				(type default)
			)
			(layer "B.Fab")
		)
		(pad "1" smd circle
			(at 0.40005 0)
			(size 0 0)
			(layers "B.Cu" "B.Mask" "B.Paste")
			(net "FT4232_SDB_EEPROM_R_CS")
		)
		(pad "2" smd circle
			(at -0.40005 0)
			(size 0 0)
			(layers "B.Cu" "B.Mask" "B.Paste")
			(net "FT4232_SDB_EEPROM_CS")
		)
	)
)
